(kicad_pcb
	(version 20260206)
	(generator "pcbnew")
	(generator_version "10.0")
	(general
		(thickness 1.6)
		(legacy_teardrops no)
	)
	(paper "A4")
	(title_block
		(title "Wiwynn_Tioga_Pass_MB.brd")
		(comment 1 "Tioga Pass / footprints 4343-4350 of 4770")
	)
	(layers
		(0 "F.Cu" signal "TOP")
		(4 "In1.Cu" signal "L2GND")
		(6 "In2.Cu" signal "L3")
		(8 "In3.Cu" signal "L4GND")
		(10 "In4.Cu" signal "L5")
		(12 "In5.Cu" signal "L6GND")
		(14 "In6.Cu" signal "L7VCC")
		(16 "In7.Cu" signal "L8VCC")
		(18 "In8.Cu" signal "L9GND")
		(20 "In9.Cu" signal "L10")
		(22 "In10.Cu" signal "L11GND")
		(24 "In11.Cu" signal "L12")
		(26 "In12.Cu" signal "L13GND")
		(2 "B.Cu" signal "BOTTOM")
		(9 "F.Adhes" user "F.Adhesive")
		(11 "B.Adhes" user "B.Adhesive")
		(13 "F.Paste" user "Package Geometry/Pastemask Top")
		(15 "B.Paste" user "Package Geometry/Pastemask Bottom")
		(5 "F.SilkS" user "Ref Des/Silkscreen Top")
		(7 "B.SilkS" user "Ref Des/Silkscreen Bottom")
		(1 "F.Mask" user "Board Geometry/Soldermask Top")
		(3 "B.Mask" user "Board Geometry/Soldermask Bottom")
		(17 "Dwgs.User" user "User.Drawings")
		(19 "Cmts.User" user "User.Comments")
		(21 "Eco1.User" user "User.Eco1")
		(23 "Eco2.User" user "User.Eco2")
		(25 "Edge.Cuts" user "Board Geometry/Outline")
		(27 "Margin" user)
		(31 "F.CrtYd" user "Package Geometry/Place Bound Top")
		(29 "B.CrtYd" user "Package Geometry/Place Bound Bottom")
		(35 "F.Fab" user "Ref Des/Assembly Top")
		(33 "B.Fab" user "Ref Des/Assembly Bottom")
	)
	(footprint ""
		(layer "B.Cu")
		(at 392.835384 -113.080038)
		(property "Reference" "R2M6"
			(at 0 0 0)
			(layer "B.SilkS")
			(hide yes)
			(effects
				(font
					(size 1.27 1.27)
				)
				(justify mirror)
			)
		)
		(property "Value" ""
			(at 0 0 0)
			(layer "B.Fab")
			(effects
				(font
					(size 1.27 1.27)
				)
				(justify mirror)
			)
		)
		(duplicate_pad_numbers_are_jumpers no)
		(fp_poly
			(pts
				(xy 0.2794 -0.1016) (xy -0.2794 -0.1016) (xy -0.2794 0.9906) (xy 0.2794 0.9906)
			)
			(stroke
				(width 0)
				(type default)
			)
			(fill no)
			(layer "B.CrtYd")
		)
		(fp_line
			(start -0.2794 -0.1016)
			(end 0.2794 -0.1016)
			(stroke
				(width 0.1)
				(type default)
			)
			(layer "B.Fab")
		)
		(fp_line
			(start -0.2794 0.9906)
			(end -0.2794 -0.1016)
			(stroke
				(width 0.1)
				(type default)
			)
			(layer "B.Fab")
		)
		(fp_line
			(start 0.2794 -0.1016)
			(end 0.2794 0.9906)
			(stroke
				(width 0.1)
				(type default)
			)
			(layer "B.Fab")
		)
		(fp_line
			(start 0.2794 0.9906)
			(end -0.2794 0.9906)
			(stroke
				(width 0.1)
				(type default)
			)
			(layer "B.Fab")
		)
		(pad "1" smd rect
			(at 0 0 180)
			(size 0.508 0.508)
			(layers "B.Cu" "B.Mask" "B.Paste")
			(net "A_KR1_RBIAS")
		)
		(pad "2" smd rect
			(at 0 0.889 180)
			(size 0.508 0.508)
			(layers "B.Cu" "B.Mask" "B.Paste")
			(net "P1V05_PCH_STBY_KR_PLL")
		)
		(zone
			(layer "B.Cu")
			(hatch none 0.5)
			(connect_pads
				(clearance 0)
			)
			(min_thickness 0.25)
			(keepout
				(tracks allowed)
				(vias not_allowed)
				(pads allowed)
				(copperpour not_allowed)
				(footprints allowed)
			)
			(placement
				(enabled no)
				(sheetname "")
			)
			(fill
				(thermal_gap 0.5)
				(thermal_bridge_width 0.5)
				(island_removal_mode 0)
			)
			(polygon
				(pts
					(xy 393.089384 -112.826038) (xy 392.581384 -112.826038) (xy 392.581384 -112.445038) (xy 393.089384 -112.445038)
				)
			)
		)
		(zone
			(layer "B.Cu")
			(hatch none 0.5)
			(connect_pads
				(clearance 0)
			)
			(min_thickness 0.25)
			(keepout
				(tracks not_allowed)
				(vias allowed)
				(pads allowed)
				(copperpour not_allowed)
				(footprints allowed)
			)
			(placement
				(enabled no)
				(sheetname "")
			)
			(fill
				(thermal_gap 0.5)
				(thermal_bridge_width 0.5)
				(island_removal_mode 0)
			)
			(polygon
				(pts
					(xy 393.089384 -112.445038) (xy 392.581384 -112.445038) (xy 392.581384 -112.826038) (xy 393.089384 -112.826038)
				)
			)
		)
	)
	(footprint ""
		(layer "B.Cu")
		(at 172.8724 -12.1412)
		(property "Reference" "C6U6"
			(at 0 0 0)
			(layer "B.SilkS")
			(hide yes)
			(effects
				(font
					(size 1.27 1.27)
				)
				(justify mirror)
			)
		)
		(property "Value" ""
			(at 0 0 0)
			(layer "B.Fab")
			(effects
				(font
					(size 1.27 1.27)
				)
				(justify mirror)
			)
		)
		(duplicate_pad_numbers_are_jumpers no)
		(fp_rect
			(start 0.4953 1.6002)
			(end -0.4953 -0.2032)
			(stroke
				(width 0)
				(type default)
			)
			(fill no)
			(layer "B.CrtYd")
		)
		(fp_line
			(start -0.4953 -0.2032)
			(end -0.4953 1.6002)
			(stroke
				(width 0.1)
				(type default)
			)
			(layer "B.Fab")
		)
		(fp_line
			(start -0.4953 1.6002)
			(end 0.4953 1.6002)
			(stroke
				(width 0.1)
				(type default)
			)
			(layer "B.Fab")
		)
		(fp_line
			(start 0.4953 -0.2032)
			(end -0.4953 -0.2032)
			(stroke
				(width 0.1)
				(type default)
			)
			(layer "B.Fab")
		)
		(fp_line
			(start 0.4953 1.6002)
			(end 0.4953 -0.2032)
			(stroke
				(width 0.1)
				(type default)
			)
			(layer "B.Fab")
		)
		(pad "1" smd rect
			(at 0 0 180)
			(size 0.762 0.889)
			(layers "B.Cu" "B.Mask" "B.Paste")
			(net "VR_VB_PVPP_GHJ")
		)
		(pad "2" smd rect
			(at 0 1.397 180)
			(size 0.762 0.889)
			(layers "B.Cu" "B.Mask" "B.Paste")
			(net "AGND_PVPP_GHJ")
		)
		(zone
			(layer "B.Cu")
			(hatch none 0.5)
			(connect_pads
				(clearance 0)
			)
			(min_thickness 0.25)
			(keepout
				(tracks not_allowed)
				(vias allowed)
				(pads allowed)
				(copperpour not_allowed)
				(footprints allowed)
			)
			(placement
				(enabled no)
				(sheetname "")
			)
			(fill
				(thermal_gap 0.5)
				(thermal_bridge_width 0.5)
				(island_removal_mode 0)
			)
			(polygon
				(pts
					(xy 173.2534 -11.1887) (xy 173.2534 -11.6967) (xy 172.4914 -11.6967) (xy 172.4914 -11.1887)
				)
			)
		)
	)
	(footprint ""
		(layer "B.Cu")
		(at 106.762296 -156.910024 -90)
		(property "Reference" "C8L1"
			(at 0 0 90)
			(layer "B.SilkS")
			(hide yes)
			(effects
				(font
					(size 1.27 1.27)
				)
				(justify mirror)
			)
		)
		(property "Value" ""
			(at 0 0 90)
			(layer "B.Fab")
			(effects
				(font
					(size 1.27 1.27)
				)
				(justify mirror)
			)
		)
		(duplicate_pad_numbers_are_jumpers no)
		(fp_poly
			(pts
				(xy 0.7239 -0.2159) (xy -0.7239 -0.2159) (xy -0.7239 1.9939) (xy 0.7239 1.9939)
			)
			(stroke
				(width 0)
				(type default)
			)
			(fill no)
			(layer "B.CrtYd")
		)
		(fp_line
			(start -0.7239 1.9939)
			(end -0.7239 -0.2159)
			(stroke
				(width 0.1)
				(type default)
			)
			(layer "B.Fab")
		)
		(fp_line
			(start 0.7239 1.9939)
			(end -0.7239 1.9939)
			(stroke
				(width 0.1)
				(type default)
			)
			(layer "B.Fab")
		)
		(fp_line
			(start -0.7239 -0.2159)
			(end 0.7239 -0.2159)
			(stroke
				(width 0.1)
				(type default)
			)
			(layer "B.Fab")
		)
		(fp_line
			(start 0.7239 -0.2159)
			(end 0.7239 1.9939)
			(stroke
				(width 0.1)
				(type default)
			)
			(layer "B.Fab")
		)
		(pad "1" smd rect
			(at 0 0 90)
			(size 1.27 1.016)
			(layers "B.Cu" "B.Mask" "B.Paste")
			(net "PVDDQ_KLM")
		)
		(pad "2" smd rect
			(at 0 1.778 90)
			(size 1.27 1.016)
			(layers "B.Cu" "B.Mask" "B.Paste")
			(net "GND")
		)
		(zone
			(layer "B.Cu")
			(hatch none 0.5)
			(connect_pads
				(clearance 0)
			)
			(min_thickness 0.25)
			(keepout
				(tracks not_allowed)
				(vias allowed)
				(pads allowed)
				(copperpour not_allowed)
				(footprints allowed)
			)
			(placement
				(enabled no)
				(sheetname "")
			)
			(fill
				(thermal_gap 0.5)
				(thermal_bridge_width 0.5)
				(island_removal_mode 0)
			)
			(polygon
				(pts
					(xy 106.254296 -156.275024) (xy 106.254296 -157.545024) (xy 105.492296 -157.545024) (xy 105.492296 -156.275024)
				)
			)
		)
	)
	(footprint ""
		(layer "B.Cu")
		(at 113.44148 -124.655834 90)
		(property "Reference" "C7M5"
			(at -1.71831 0.57658 0)
			(unlocked yes)
			(layer "B.SilkS")
			(effects
				(font
					(size 0.7874 0.5842)
					(thickness 0.1524)
				)
				(justify mirror)
			)
		)
		(property "Value" ""
			(at 0 0 90)
			(layer "B.Fab")
			(effects
				(font
					(size 1.27 1.27)
				)
				(justify mirror)
			)
		)
		(duplicate_pad_numbers_are_jumpers no)
		(fp_rect
			(start 0.500126 1.598422)
			(end -0.500126 -0.201422)
			(stroke
				(width 0)
				(type default)
			)
			(fill no)
			(layer "B.CrtYd")
		)
		(fp_line
			(start 0.500126 -0.201422)
			(end -0.500126 -0.201422)
			(stroke
				(width 0.1)
				(type default)
			)
			(layer "B.Fab")
		)
		(fp_line
			(start -0.500126 -0.201422)
			(end -0.500126 1.598422)
			(stroke
				(width 0.1)
				(type default)
			)
			(layer "B.Fab")
		)
		(fp_line
			(start 0.500126 1.598422)
			(end 0.500126 -0.201422)
			(stroke
				(width 0.1)
				(type default)
			)
			(layer "B.Fab")
		)
		(fp_line
			(start -0.500126 1.598422)
			(end 0.500126 1.598422)
			(stroke
				(width 0.1)
				(type default)
			)
			(layer "B.Fab")
		)
		(pad "1" smd rect
			(at 0 0)
			(size 0.889 0.9906)
			(layers "B.Cu" "B.Mask" "B.Paste")
			(net "PVDDQ_KLM")
		)
		(pad "2" smd rect
			(at 0 1.397)
			(size 0.889 0.9906)
			(layers "B.Cu" "B.Mask" "B.Paste")
			(net "GND")
		)
		(zone
			(layer "B.Cu")
			(hatch none 0.5)
			(connect_pads
				(clearance 0)
			)
			(min_thickness 0.25)
			(keepout
				(tracks allowed)
				(vias not_allowed)
				(pads allowed)
				(copperpour not_allowed)
				(footprints allowed)
			)
			(placement
				(enabled no)
				(sheetname "")
			)
			(fill
				(thermal_gap 0.5)
				(thermal_bridge_width 0.5)
				(island_removal_mode 0)
			)
			(polygon
				(pts
					(xy 114.39398 -125.151134) (xy 113.88598 -125.151134) (xy 113.88598 -124.160534) (xy 114.39398 -124.160534)
				)
			)
		)
		(zone
			(layer "B.Cu")
			(hatch none 0.5)
			(connect_pads
				(clearance 0)
			)
			(min_thickness 0.25)
			(keepout
				(tracks not_allowed)
				(vias allowed)
				(pads allowed)
				(copperpour not_allowed)
				(footprints allowed)
			)
			(placement
				(enabled no)
				(sheetname "")
			)
			(fill
				(thermal_gap 0.5)
				(thermal_bridge_width 0.5)
				(island_removal_mode 0)
			)
			(polygon
				(pts
					(xy 114.39398 -125.151134) (xy 113.88598 -125.151134) (xy 113.88598 -124.160534) (xy 114.39398 -124.160534)
				)
			)
		)
	)
	(footprint ""
		(layer "B.Cu")
		(at 468.341202 -36.435792 -90)
		(property "Reference" "C1T15"
			(at 0 0 90)
			(layer "B.SilkS")
			(hide yes)
			(effects
				(font
					(size 1.27 1.27)
				)
				(justify mirror)
			)
		)
		(property "Value" ""
			(at 0 0 90)
			(layer "B.Fab")
			(effects
				(font
					(size 1.27 1.27)
				)
				(justify mirror)
			)
		)
		(duplicate_pad_numbers_are_jumpers no)
		(fp_poly
			(pts
				(xy 0.4953 -0.2032) (xy -0.4953 -0.2032) (xy -0.4953 1.6002) (xy 0.4953 1.6002)
			)
			(stroke
				(width 0)
				(type default)
			)
			(fill no)
			(layer "B.CrtYd")
		)
		(fp_line
			(start -0.4953 1.6002)
			(end 0.4953 1.6002)
			(stroke
				(width 0.1)
				(type default)
			)
			(layer "B.Fab")
		)
		(fp_line
			(start 0.4953 1.6002)
			(end 0.4953 -0.2032)
			(stroke
				(width 0.1)
				(type default)
			)
			(layer "B.Fab")
		)
		(fp_line
			(start -0.4953 -0.2032)
			(end -0.4953 1.6002)
			(stroke
				(width 0.1)
				(type default)
			)
			(layer "B.Fab")
		)
		(fp_line
			(start 0.4953 -0.2032)
			(end -0.4953 -0.2032)
			(stroke
				(width 0.1)
				(type default)
			)
			(layer "B.Fab")
		)
		(pad "1" smd rect
			(at 0 0 90)
			(size 0.762 0.889)
			(layers "B.Cu" "B.Mask" "B.Paste")
			(net "P1V2_AUX_BMC")
		)
		(pad "2" smd rect
			(at 0 1.397 90)
			(size 0.762 0.889)
			(layers "B.Cu" "B.Mask" "B.Paste")
			(net "GND")
		)
		(zone
			(layer "B.Cu")
			(hatch none 0.5)
			(connect_pads
				(clearance 0)
			)
			(min_thickness 0.25)
			(keepout
				(tracks not_allowed)
				(vias allowed)
				(pads allowed)
				(copperpour not_allowed)
				(footprints allowed)
			)
			(placement
				(enabled no)
				(sheetname "")
			)
			(fill
				(thermal_gap 0.5)
				(thermal_bridge_width 0.5)
				(island_removal_mode 0)
			)
			(polygon
				(pts
					(xy 467.896702 -36.054792) (xy 467.896702 -36.816792) (xy 467.388702 -36.816792) (xy 467.388702 -36.054792)
				)
			)
		)
	)
	(footprint ""
		(layer "B.Cu")
		(at 378.587 -49.276 90)
		(property "Reference" "R3T2"
			(at 0 0 90)
			(layer "B.SilkS")
			(hide yes)
			(effects
				(font
					(size 1.27 1.27)
				)
				(justify mirror)
			)
		)
		(property "Value" ""
			(at 0 0 90)
			(layer "B.Fab")
			(effects
				(font
					(size 1.27 1.27)
				)
				(justify mirror)
			)
		)
		(duplicate_pad_numbers_are_jumpers no)
		(fp_poly
			(pts
				(xy 0.2794 -0.1016) (xy -0.2794 -0.1016) (xy -0.2794 0.9906) (xy 0.2794 0.9906)
			)
			(stroke
				(width 0)
				(type default)
			)
			(fill no)
			(layer "B.CrtYd")
		)
		(fp_line
			(start 0.2794 -0.1016)
			(end 0.2794 0.9906)
			(stroke
				(width 0.1)
				(type default)
			)
			(layer "B.Fab")
		)
		(fp_line
			(start -0.2794 -0.1016)
			(end 0.2794 -0.1016)
			(stroke
				(width 0.1)
				(type default)
			)
			(layer "B.Fab")
		)
		(fp_line
			(start 0.2794 0.9906)
			(end -0.2794 0.9906)
			(stroke
				(width 0.1)
				(type default)
			)
			(layer "B.Fab")
		)
		(fp_line
			(start -0.2794 0.9906)
			(end -0.2794 -0.1016)
			(stroke
				(width 0.1)
				(type default)
			)
			(layer "B.Fab")
		)
		(pad "1" smd rect
			(at 0 0 270)
			(size 0.508 0.508)
			(layers "B.Cu" "B.Mask" "B.Paste")
			(net "SPI_SWITCH_MISO")
		)
		(pad "2" smd rect
			(at 0 0.889 270)
			(size 0.508 0.508)
			(layers "B.Cu" "B.Mask" "B.Paste")
			(net "SPI_MISO_R1")
		)
		(zone
			(layer "B.Cu")
			(hatch none 0.5)
			(connect_pads
				(clearance 0)
			)
			(min_thickness 0.25)
			(keepout
				(tracks allowed)
				(vias not_allowed)
				(pads allowed)
				(copperpour not_allowed)
				(footprints allowed)
			)
			(placement
				(enabled no)
				(sheetname "")
			)
			(fill
				(thermal_gap 0.5)
				(thermal_bridge_width 0.5)
				(island_removal_mode 0)
			)
			(polygon
				(pts
					(xy 378.841 -49.53) (xy 378.841 -49.022) (xy 379.222 -49.022) (xy 379.222 -49.53)
				)
			)
		)
		(zone
			(layer "B.Cu")
			(hatch none 0.5)
			(connect_pads
				(clearance 0)
			)
			(min_thickness 0.25)
			(keepout
				(tracks not_allowed)
				(vias allowed)
				(pads allowed)
				(copperpour not_allowed)
				(footprints allowed)
			)
			(placement
				(enabled no)
				(sheetname "")
			)
			(fill
				(thermal_gap 0.5)
				(thermal_bridge_width 0.5)
				(island_removal_mode 0)
			)
			(polygon
				(pts
					(xy 379.222 -49.53) (xy 379.222 -49.022) (xy 378.841 -49.022) (xy 378.841 -49.53)
				)
			)
		)
	)
	(footprint ""
		(layer "B.Cu")
		(at 412.3055 -34.925 90)
		(property "Reference" "C25W23"
			(at 0.8382 -0.67818 90)
			(unlocked yes)
			(layer "B.SilkS")
			(effects
				(font
					(size 0.4064 0.254)
					(thickness 0.1524)
				)
				(justify left mirror)
			)
		)
		(property "Value" ""
			(at 0 0 90)
			(layer "B.Fab")
			(effects
				(font
					(size 1.27 1.27)
				)
				(justify mirror)
			)
		)
		(duplicate_pad_numbers_are_jumpers no)
		(fp_poly
			(pts
				(xy -0.3048 -0.1016) (xy -0.3048 0.9906) (xy 0.3048 0.9906) (xy 0.3048 -0.1016)
			)
			(stroke
				(width 0)
				(type default)
			)
			(fill no)
			(layer "B.CrtYd")
		)
		(fp_line
			(start 0.3048 -0.1016)
			(end 0.3048 0.9906)
			(stroke
				(width 0.1)
				(type default)
			)
			(layer "B.Fab")
		)
		(fp_line
			(start -0.3048 -0.1016)
			(end 0.3048 -0.1016)
			(stroke
				(width 0.1)
				(type default)
			)
			(layer "B.Fab")
		)
		(fp_line
			(start 0.3048 0.9906)
			(end -0.3048 0.9906)
			(stroke
				(width 0.1)
				(type default)
			)
			(layer "B.Fab")
		)
		(fp_line
			(start -0.3048 0.9906)
			(end -0.3048 -0.1016)
			(stroke
				(width 0.1)
				(type default)
			)
			(layer "B.Fab")
		)
		(pad "1" smd rect
			(at 0 0 270)
			(size 0.508 0.508)
			(layers "B.Cu" "B.Mask" "B.Paste")
			(net "P1V15_AUX_BMC")
		)
		(pad "2" smd rect
			(at 0 0.889 270)
			(size 0.508 0.508)
			(layers "B.Cu" "B.Mask" "B.Paste")
			(net "GND")
		)
		(zone
			(layer "B.Cu")
			(hatch none 0.5)
			(connect_pads
				(clearance 0)
			)
			(min_thickness 0.25)
			(keepout
				(tracks allowed)
				(vias not_allowed)
				(pads allowed)
				(copperpour not_allowed)
				(footprints allowed)
			)
			(placement
				(enabled no)
				(sheetname "")
			)
			(fill
				(thermal_gap 0.5)
				(thermal_bridge_width 0.5)
				(island_removal_mode 0)
			)
			(polygon
				(pts
					(xy 412.5595 -35.179) (xy 412.5595 -34.671) (xy 412.9405 -34.671) (xy 412.9405 -35.179)
				)
			)
		)
		(zone
			(layer "B.Cu")
			(hatch none 0.5)
			(connect_pads
				(clearance 0)
			)
			(min_thickness 0.25)
			(keepout
				(tracks not_allowed)
				(vias allowed)
				(pads allowed)
				(copperpour not_allowed)
				(footprints allowed)
			)
			(placement
				(enabled no)
				(sheetname "")
			)
			(fill
				(thermal_gap 0.5)
				(thermal_bridge_width 0.5)
				(island_removal_mode 0)
			)
			(polygon
				(pts
					(xy 412.9405 -35.179) (xy 412.9405 -34.671) (xy 412.5595 -34.671) (xy 412.5595 -35.179)
				)
			)
		)
	)
	(footprint ""
		(layer "B.Cu")
		(at 368.189256 -92.100654 90)
		(property "Reference" "R7W21"
			(at 0.8382 -0.67818 90)
			(unlocked yes)
			(layer "B.SilkS")
			(effects
				(font
					(size 0.4064 0.254)
					(thickness 0.1524)
				)
				(justify left mirror)
			)
		)
		(property "Value" ""
			(at 0 0 90)
			(layer "B.Fab")
			(effects
				(font
					(size 1.27 1.27)
				)
				(justify mirror)
			)
		)
		(duplicate_pad_numbers_are_jumpers no)
		(fp_poly
			(pts
				(xy 0.2794 -0.1016) (xy -0.2794 -0.1016) (xy -0.2794 0.9906) (xy 0.2794 0.9906)
			)
			(stroke
				(width 0)
				(type default)
			)
			(fill no)
			(layer "B.CrtYd")
		)
		(fp_line
			(start 0.2794 -0.1016)
			(end 0.2794 0.9906)
			(stroke
				(width 0.1)
				(type default)
			)
			(layer "B.Fab")
		)
		(fp_line
			(start -0.2794 -0.1016)
			(end 0.2794 -0.1016)
			(stroke
				(width 0.1)
				(type default)
			)
			(layer "B.Fab")
		)
		(fp_line
			(start 0.2794 0.9906)
			(end -0.2794 0.9906)
			(stroke
				(width 0.1)
				(type default)
			)
			(layer "B.Fab")
		)
		(fp_line
			(start -0.2794 0.9906)
			(end -0.2794 -0.1016)
			(stroke
				(width 0.1)
				(type default)
			)
			(layer "B.Fab")
		)
		(pad "1" smd rect
			(at 0 0 270)
			(size 0.508 0.508)
			(layers "B.Cu" "B.Mask" "B.Paste")
			(net "P3V3_STBY")
		)
		(pad "2" smd rect
			(at 0 0.889 270)
			(size 0.508 0.508)
			(layers "B.Cu" "B.Mask" "B.Paste")
			(net "RST_BMC_SRST_R_N")
		)
		(zone
			(layer "B.Cu")
			(hatch none 0.5)
			(connect_pads
				(clearance 0)
			)
			(min_thickness 0.25)
			(keepout
				(tracks allowed)
				(vias not_allowed)
				(pads allowed)
				(copperpour not_allowed)
				(footprints allowed)
			)
			(placement
				(enabled no)
				(sheetname "")
			)
			(fill
				(thermal_gap 0.5)
				(thermal_bridge_width 0.5)
				(island_removal_mode 0)
			)
			(polygon
				(pts
					(xy 368.443256 -92.354654) (xy 368.443256 -91.846654) (xy 368.824256 -91.846654) (xy 368.824256 -92.354654)
				)
			)
		)
		(zone
			(layer "B.Cu")
			(hatch none 0.5)
			(connect_pads
				(clearance 0)
			)
			(min_thickness 0.25)
			(keepout
				(tracks not_allowed)
				(vias allowed)
				(pads allowed)
				(copperpour not_allowed)
				(footprints allowed)
			)
			(placement
				(enabled no)
				(sheetname "")
			)
			(fill
				(thermal_gap 0.5)
				(thermal_bridge_width 0.5)
				(island_removal_mode 0)
			)
			(polygon
				(pts
					(xy 368.824256 -92.354654) (xy 368.824256 -91.846654) (xy 368.443256 -91.846654) (xy 368.443256 -92.354654)
				)
			)
		)
	)
)
